# T6G (Grand Teton) — schematic netlist excerpt (pin names and nets, part order shuffled) for the footprints in the layout excerpt that follows; sources: Cadence DE-HDL packaged netlist, KiCad conversion of 04192023_DAF0TMB3IC0_F0TG_MB_C_brd_V02_OCP.brd

J15  SCONN288_DDR506112002KQ  IO  pkg DDR288S_1-1VXC  page 87
  VIN_BULK0  = P12V_MEM_CPU0
  RFU0  = NC
  VIN_MGMT  = P3V3_AUX
  HSCL  = I3C_SPD_DDRB_CPU0_SCL
  HSDA  = I3C_SPD_DDRB_CPU0_SDA
  VSS0  = GND
  DQ0_A  = M_B_CPU0_SA_DQ<0>
  VSS1  = GND
  DQ1_A  = M_B_CPU0_SA_DQ<1>
  VSS2  = GND
  DQS0_A_T  = M_B_CPU0_SA_DQS_DP<0>
  DQS0_A_C  = M_B_CPU0_SA_DQS_DN<0>
  VSS3  = GND
  DQ4_A  = M_B_CPU0_SA_DQ<4>
  VSS4  = GND
  DQ5_A  = M_B_CPU0_SA_DQ<5>
  VSS5  = GND
  DQ8_A  = M_B_CPU0_SA_DQ<8>
  VSS6  = GND
  DQ9_A  = M_B_CPU0_SA_DQ<9>
  VSS7  = GND
  DQS1_A_T  = M_B_CPU0_SA_DQS_DP<1>
  DQS1_A_C  = M_B_CPU0_SA_DQS_DN<1>
  VSS8  = GND
  DQ12_A  = M_B_CPU0_SA_DQ<12>
  VSS9  = GND
  DQ13_A  = M_B_CPU0_SA_DQ<13>
  VSS10  = GND
  DQ16_A  = M_B_CPU0_SA_DQ<16>
  VSS11  = GND
  DQ17_A  = M_B_CPU0_SA_DQ<17>
  VSS12  = GND
  DQS2_A_T  = M_B_CPU0_SA_DQS_DP<2>
  DQS2_A_C  = M_B_CPU0_SA_DQS_DN<2>
  VSS13  = GND
  DQ20_A  = M_B_CPU0_SA_DQ<20>
  VSS14  = GND
  DQ21_A  = M_B_CPU0_SA_DQ<21>
  VSS15  = GND
  DQ24_A  = M_B_CPU0_SA_DQ<24>
  VSS16  = GND
  DQ25_A  = M_B_CPU0_SA_DQ<25>
  VSS17  = GND
  DQS3_A_T  = M_B_CPU0_SA_DQS_DP<3>
  DQS3_A_C  = M_B_CPU0_SA_DQS_DN<3>
  VSS18  = GND
  DQ28_A  = M_B_CPU0_SA_DQ<28>
  VSS19  = GND
  DQ29_A  = M_B_CPU0_SA_DQ<29>
  VSS20  = GND
  CB0_A  = M_B_CPU0_SA_CB<0>
  VSS21  = GND
  CB1_A  = M_B_CPU0_SA_CB<1>
  VSS22  = GND
  DQS4_A_T  = M_B_CPU0_SA_DQS_DP<4>
  DQS4_A_C  = M_B_CPU0_SA_DQS_DN<4>
  VSS23  = GND
  CB4_A  = M_B_CPU0_SA_CB<4>
  VSS24  = GND
  CB5_A  = M_B_CPU0_SA_CB<5>
  VSS25  = GND
  ALERT_N  = M_B_CPU0_ALERT_N
  VSS26  = GND
  CS0_A_N  = M_B_CPU0_SA_CS_N<0>
  VSS27  = GND
  CA0_A  = M_B_CPU0_SA_CA<0>
  VSS28  = GND
  CA2_A  = M_B_CPU0_SA_CA<2>
  VSS29  = GND
  CA4_A  = M_B_CPU0_SA_CA<4>
  VSS30  = GND
  CA6_A  = M_B_CPU0_SA_CA<6>
  VSS31  = GND
  PAR_A  = M_B_CPU0_SA_PAR
  VSS32  = GND
  CA0_B  = M_B_CPU0_SB_CA<0>
  VSS33  = GND
  CA2_B  = M_B_CPU0_SB_CA<2>
  VSS34  = GND
  CA4_B  = M_B_CPU0_SB_CA<4>
  VSS35  = GND
  CA6_B  = M_B_CPU0_SB_CA<6>
  VSS36  = GND
  CS0_B_N  = M_B_CPU0_SB_CS_N<0>
  VSS37  = GND
  \lbd||rsp_a_n\  = M_B_CPU0_SA_RSP<0>
  \lbs||rsp_b_n\  = M_B_CPU0_SB_RSP<0>
  VSS38  = GND
  CB4_B  = M_B_CPU0_SB_CB<4>
  VSS39  = GND
  CB5_B  = M_B_CPU0_SB_CB<5>
  VSS40  = GND
  \dqs9_b_t||tdqs9_b_t||dbi4_b_n\  = M_B_CPU0_SB_DQS_DP<9>
  \dqs9_b_c||tdqs9_b_c\  = M_B_CPU0_SB_DQS_DN<9>
  VSS41  = GND
  CB0_B  = M_B_CPU0_SB_CB<0>
  VSS42  = GND
  CB1_B  = M_B_CPU0_SB_CB<1>
  VSS43  = GND
  DQ0_B  = M_B_CPU0_SB_DQ<0>
  VSS44  = GND
  DQ1_B  = M_B_CPU0_SB_DQ<1>
  VSS45  = GND
  DQS0_B_T  = M_B_CPU0_SB_DQS_DP<0>
  DQS0_B_C  = M_B_CPU0_SB_DQS_DN<0>
  VSS46  = GND
  DQ4_B  = M_B_CPU0_SB_DQ<4>
  VSS47  = GND
  DQ5_B  = M_B_CPU0_SB_DQ<5>
  VSS48  = GND
  DQ8_B  = M_B_CPU0_SB_DQ<8>
  VSS49  = GND
  DQ9_B  = M_B_CPU0_SB_DQ<9>
  VSS50  = GND
  DQS1_B_T  = M_B_CPU0_SB_DQS_DP<1>
  DQS1_B_C  = M_B_CPU0_SB_DQS_DN<1>
  VSS51  = GND
  DQ12_B  = M_B_CPU0_SB_DQ<12>
  VSS52  = GND
  DQ13_B  = M_B_CPU0_SB_DQ<13>
  VSS53  = GND
  DQ16_B  = M_B_CPU0_SB_DQ<16>
  VSS54  = GND
  DQ17_B  = M_B_CPU0_SB_DQ<17>
  VSS55  = GND
  DQS2_B_T  = M_B_CPU0_SB_DQS_DP<2>
  DQS2_B_C  = M_B_CPU0_SB_DQS_DN<2>
  VSS56  = GND
  DQ20_B  = M_B_CPU0_SB_DQ<20>
  VSS57  = GND
  DQ21_B  = M_B_CPU0_SB_DQ<21>
  VSS58  = GND
  DQ24_B  = M_B_CPU0_SB_DQ<24>
  VSS59  = GND
  DQ25_B  = M_B_CPU0_SB_DQ<25>
  VSS60  = GND
  DQS3_B_T  = M_B_CPU0_SB_DQS_DP<3>
  DQS3_B_C  = M_B_CPU0_SB_DQS_DN<3>
  VSS61  = GND
  DQ28_B  = M_B_CPU0_SB_DQ<28>
  VSS62  = GND
  DQ29_B  = M_B_CPU0_SB_DQ<29>
  VSS63  = GND
  RFU1  = NC
  VIN_BULK1  = P12V_MEM_CPU0
  VIN_BULK2  = P12V_MEM_CPU0
  \pwr_good||fail_n\  = PWRGD_CHB_CPU0_DIMM
  HAS  = PD_CHB_CPU0_DIMM_SAA
  RFU2  = NC
  RFU3  = NC
  VSS64  = GND
  DQ2_A  = M_B_CPU0_SA_DQ<2>
  VSS65  = GND
  DQ3_A  = M_B_CPU0_SA_DQ<3>
  VSS66  = GND
  \dqs5_a_c||tdqs5_a_c||dqs5_a_t||tdqs5_a_t\  = M_B_CPU0_SA_DQS_DN<5>
  \dqs5_a_t||tdqs5_a_t\  = M_B_CPU0_SA_DQS_DP<5>
  VSS67  = GND
  DQ6_A  = M_B_CPU0_SA_DQ<6>
  VSS68  = GND
  DQ7_A  = M_B_CPU0_SA_DQ<7>
  VSS69  = GND
  DQ10_A  = M_B_CPU0_SA_DQ<10>
  VSS70  = GND
  DQ11_A  = M_B_CPU0_SA_DQ<11>
  VSS71  = GND
  \dqs6_a_c||tdqs6_a_c||dqs6_a_t||tdqs6_a_t\  = M_B_CPU0_SA_DQS_DN<6>
  \dqs6_a_t||tdqs6_a_t\  = M_B_CPU0_SA_DQS_DP<6>
  VSS72  = GND
  DQ14_A  = M_B_CPU0_SA_DQ<14>
  VSS73  = GND
  DQ15_A  = M_B_CPU0_SA_DQ<15>
  VSS74  = GND
  DQ18_A  = M_B_CPU0_SA_DQ<18>
  VSS75  = GND
  DQ19_A  = M_B_CPU0_SA_DQ<19>
  VSS76  = GND
  \dqs7_a_c||tdqs7_a_c\  = M_B_CPU0_SA_DQS_DN<7>
  \dqs7_a_t||tdqs7_a_t\  = M_B_CPU0_SA_DQS_DP<7>
  VSS77  = GND
  DQ22_A  = M_B_CPU0_SA_DQ<22>
  VSS78  = GND
  DQ23_A  = M_B_CPU0_SA_DQ<23>
  VSS79  = GND
  DQ26_A  = M_B_CPU0_SA_DQ<26>
  VSS80  = GND
  DQ27_A  = M_B_CPU0_SA_DQ<27>
  VSS81  = GND
  \dqs8_a_c||tdqs8_a_c\  = M_B_CPU0_SA_DQS_DN<8>
  \dqs8_a_t||tdqs8_a_t\  = M_B_CPU0_SA_DQS_DP<8>
  VSS82  = GND
  DQ30_A  = M_B_CPU0_SA_DQ<30>
  VSS83  = GND
  DQ31_A  = M_B_CPU0_SA_DQ<31>
  VSS84  = GND
  CB2_A  = M_B_CPU0_SA_CB<2>
  VSS85  = GND
  CB3_A  = M_B_CPU0_SA_CB<3>
  VSS86  = GND
  \dqs9_a_c||tdqs9_a_c\  = M_B_CPU0_SA_DQS_DN<9>
  \dqs9_a_t||tdqs9_a_t\  = M_B_CPU0_SA_DQS_DP<9>
  VSS87  = GND
  CB6_A  = M_B_CPU0_SA_CB<6>
  VSS88  = GND
  CB7_A  = M_B_CPU0_SA_CB<7>
  VSS89  = GND
  RESET_N  = M_B_CPU0_RESET_N
  VSS90  = GND
  CS1_A_N  = M_B_CPU0_SA_CS_N<1>
  VSS91  = GND
  CA1_A  = M_B_CPU0_SA_CA<1>
  VSS92  = GND
  CA3_A  = M_B_CPU0_SA_CA<3>
  VSS93  = GND
  CA5_A  = M_B_CPU0_SA_CA<5>
  VSS94  = GND
  CK_T  = M_B_CPU0_CLK_DP<0>
  CK_C  = M_B_CPU0_CLK_DN<0>
  VSS95  = GND
  RFU4  = NC
  CA1_B  = M_B_CPU0_SB_CA<1>
  VSS96  = GND
  CA3_B  = M_B_CPU0_SB_CA<3>
  VSS97  = GND
  CA5_B  = M_B_CPU0_SB_CA<5>
  VSS98  = GND
  PAR_B  = M_B_CPU0_SB_PAR
  VSS99  = GND
  CS1_B_N  = M_B_CPU0_SB_CS_N<1>
  VSS100  = GND
  RFU5  = NC
  RFU6  = NC
  VSS101  = GND
  CB6_B  = M_B_CPU0_SB_CB<6>
  VSS102  = GND
  CB7_B  = M_B_CPU0_SB_CB<7>
  VSS103  = GND
  DQS4_B_C  = M_B_CPU0_SB_DQS_DN<4>
  DQS4_B_T  = M_B_CPU0_SB_DQS_DP<4>
  VSS104  = GND
  CB2_B  = M_B_CPU0_SB_CB<2>
  VSS105  = GND
  CB3_B  = M_B_CPU0_SB_CB<3>
  VSS106  = GND
  DQ2_B  = M_B_CPU0_SB_DQ<2>
  VSS107  = GND
  DQ3_B  = M_B_CPU0_SB_DQ<3>
  VSS108  = GND
  \dqs5_b_c||tdqs5_b_c\  = M_B_CPU0_SB_DQS_DN<5>
  \dqs5_b_t||tdqs5_b_t\  = M_B_CPU0_SB_DQS_DP<5>
  VSS109  = GND
  DQ6_B  = M_B_CPU0_SB_DQ<6>
  VSS110  = GND
  DQ7_B  = M_B_CPU0_SB_DQ<7>
  VSS111  = GND
  DQ10_B  = M_B_CPU0_SB_DQ<10>
  VSS112  = GND
  DQ11_B  = M_B_CPU0_SB_DQ<11>
  VSS113  = GND
  \dqs6_b_c||tdqs6_b_c\  = M_B_CPU0_SB_DQS_DN<6>
  \dqs6_b_t||tdqs6_b_t\  = M_B_CPU0_SB_DQS_DP<6>
  VSS114  = GND
  DQ14_B  = M_B_CPU0_SB_DQ<14>
  VSS115  = GND
  DQ15_B  = M_B_CPU0_SB_DQ<15>
  VSS116  = GND
  DQ18_B  = M_B_CPU0_SB_DQ<18>
  VSS117  = GND
  DQ19_B  = M_B_CPU0_SB_DQ<19>
  VSS118  = GND
  \dqs7_b_c||tdqs7_b_c\  = M_B_CPU0_SB_DQS_DN<7>
  \dqs7_b_t||tdqs7_b_t\  = M_B_CPU0_SB_DQS_DP<7>
  VSS119  = GND
  DQ22_B  = M_B_CPU0_SB_DQ<22>
  VSS120  = GND
  DQ23_B  = M_B_CPU0_SB_DQ<23>
  VSS121  = GND
  DQ26_B  = M_B_CPU0_SB_DQ<26>
  VSS122  = GND
  DQ27_B  = M_B_CPU0_SB_DQ<27>
  VSS123  = GND
  \dqs8_b_c||tdqs8_b_c\  = M_B_CPU0_SB_DQS_DN<8>
  \dqs8_b_t||tdqs8_b_t\  = M_B_CPU0_SB_DQS_DP<8>
  VSS124  = GND
  DQ30_B  = M_B_CPU0_SB_DQ<30>
  VSS125  = GND
  DQ31_B  = M_B_CPU0_SB_DQ<31>
  VSS126  = GND
  G1  = GND
  G2  = GND
  G3  = GND

(kicad_pcb
	(version 20260206)
	(generator "pcbnew")
	(generator_version "10.0")
	(general
		(thickness 1.6)
		(legacy_teardrops no)
	)
	(paper "A4")
	(title_block
		(title "04192023_DAF0TMB3IC0_F0TG_MB_C_brd_V02_OCP.brd")
		(comment 1 "Grand Teton / footprint 1120 of 8354 (J15), pads 47-92 of 291")
	)
	(layers
		(0 "F.Cu" signal "TOP")
		(4 "In1.Cu" signal "GND")
		(6 "In2.Cu" signal "IN1")
		(8 "In3.Cu" signal "GND1")
		(10 "In4.Cu" signal "IN2")
		(12 "In5.Cu" signal "GND2")
		(14 "In6.Cu" signal "IN3")
		(16 "In7.Cu" signal "GND3")
		(18 "In8.Cu" signal "VCC")
		(20 "In9.Cu" signal "VCC1")
		(22 "In10.Cu" signal "GND4")
		(24 "In11.Cu" signal "IN4")
		(26 "In12.Cu" signal "GND5")
		(28 "In13.Cu" signal "IN5")
		(30 "In14.Cu" signal "GND6")
		(32 "In15.Cu" signal "IN6")
		(34 "In16.Cu" signal "GND7")
		(2 "B.Cu" signal "BOTTOM")
		(9 "F.Adhes" user "F.Adhesive")
		(11 "B.Adhes" user "B.Adhesive")
		(13 "F.Paste" user "Package Geometry/Pastemask Top")
		(15 "B.Paste" user "Package Geometry/Pastemask Bottom")
		(5 "F.SilkS" user "Ref Des/Silkscreen Top")
		(7 "B.SilkS" user "Ref Des/Silkscreen Bottom")
		(1 "F.Mask" user "Board Geometry/Soldermask Top")
		(3 "B.Mask" user "Board Geometry/Soldermask Bottom")
		(17 "Dwgs.User" user "User.Drawings")
		(19 "Cmts.User" user "User.Comments")
		(21 "Eco1.User" user "User.Eco1")
		(23 "Eco2.User" user "User.Eco2")
		(25 "Edge.Cuts" user "Board Geometry/Outline")
		(27 "Margin" user)
		(31 "F.CrtYd" user "Package Geometry/Place Bound Top")
		(29 "B.CrtYd" user "Package Geometry/Place Bound Bottom")
		(35 "F.Fab" user "Ref Des/Assembly Top")
		(33 "B.Fab" user "Ref Des/Assembly Bottom")
	)
	(footprint ""
		(layer "F.Cu")
		(at 297.774106 -255.560068 180)
		(property "Reference" "J15"
			(at -2.2098 -81.984088 0)
			(unlocked yes)
			(layer "F.SilkS")
			(effects
				(font
					(size 0.7874 0.5842)
					(thickness 0.1524)
				)
			)
		)
		(property "Value" ""
			(at 0 0 180)
			(layer "F.Fab")
			(effects
				(font
					(size 1.27 1.27)
				)
			)
		)
		(duplicate_pad_numbers_are_jumpers no)
		(pad "47" smd rect
			(at -2.050034 -24.224996 90)
			(size 0.519938 1.4986)
			(layers "F.Cu" "F.Mask" "F.Paste")
			(net "M_B_CPU0_SA_DQ<28>")
		)
		(pad "48" smd rect
			(at -2.050034 -23.375112 90)
			(size 0.519938 1.4986)
			(layers "F.Cu" "F.Mask" "F.Paste")
			(net "GND")
		)
		(pad "49" smd rect
			(at -2.050034 -22.524974 90)
			(size 0.519938 1.4986)
			(layers "F.Cu" "F.Mask" "F.Paste")
			(net "M_B_CPU0_SA_DQ<29>")
		)
		(pad "50" smd rect
			(at -2.050034 -21.67509 90)
			(size 0.519938 1.4986)
			(layers "F.Cu" "F.Mask" "F.Paste")
			(net "GND")
		)
		(pad "51" smd rect
			(at -2.050034 -20.824952 90)
			(size 0.519938 1.4986)
			(layers "F.Cu" "F.Mask" "F.Paste")
			(net "M_B_CPU0_SA_CB<0>")
		)
		(pad "52" smd rect
			(at -2.050034 -19.975068 90)
			(size 0.519938 1.4986)
			(layers "F.Cu" "F.Mask" "F.Paste")
			(net "GND")
		)
		(pad "53" smd rect
			(at -2.050034 -19.12493 90)
			(size 0.519938 1.4986)
			(layers "F.Cu" "F.Mask" "F.Paste")
			(net "M_B_CPU0_SA_CB<1>")
		)
		(pad "54" smd rect
			(at -2.050034 -18.275046 90)
			(size 0.519938 1.4986)
			(layers "F.Cu" "F.Mask" "F.Paste")
			(net "GND")
		)
		(pad "55" smd rect
			(at -2.050034 -17.424908 90)
			(size 0.519938 1.4986)
			(layers "F.Cu" "F.Mask" "F.Paste")
			(net "M_B_CPU0_SA_DQS_DP<4>")
		)
		(pad "56" smd rect
			(at -2.050034 -16.575024 90)
			(size 0.519938 1.4986)
			(layers "F.Cu" "F.Mask" "F.Paste")
			(net "M_B_CPU0_SA_DQS_DN<4>")
		)
		(pad "57" smd rect
			(at -2.050034 -15.724886 90)
			(size 0.519938 1.4986)
			(layers "F.Cu" "F.Mask" "F.Paste")
			(net "GND")
		)
		(pad "58" smd rect
			(at -2.050034 -14.875002 90)
			(size 0.519938 1.4986)
			(layers "F.Cu" "F.Mask" "F.Paste")
			(net "M_B_CPU0_SA_CB<4>")
		)
		(pad "59" smd rect
			(at -2.050034 -14.025118 90)
			(size 0.519938 1.4986)
			(layers "F.Cu" "F.Mask" "F.Paste")
			(net "GND")
		)
		(pad "60" smd rect
			(at -2.050034 -13.17498 90)
			(size 0.519938 1.4986)
			(layers "F.Cu" "F.Mask" "F.Paste")
			(net "M_B_CPU0_SA_CB<5>")
		)
		(pad "61" smd rect
			(at -2.050034 -12.325096 90)
			(size 0.519938 1.4986)
			(layers "F.Cu" "F.Mask" "F.Paste")
			(net "GND")
		)
		(pad "62" smd rect
			(at -2.050034 -11.474958 90)
			(size 0.519938 1.4986)
			(layers "F.Cu" "F.Mask" "F.Paste")
			(net "M_B_CPU0_ALERT_N")
		)
		(pad "63" smd rect
			(at -2.050034 -10.625074 90)
			(size 0.519938 1.4986)
			(layers "F.Cu" "F.Mask" "F.Paste")
			(net "GND")
		)
		(pad "64" smd rect
			(at -2.050034 -9.774936 90)
			(size 0.519938 1.4986)
			(layers "F.Cu" "F.Mask" "F.Paste")
			(net "M_B_CPU0_SA_CS_N<0>")
		)
		(pad "65" smd rect
			(at -2.050034 -8.925052 90)
			(size 0.519938 1.4986)
			(layers "F.Cu" "F.Mask" "F.Paste")
			(net "GND")
		)
		(pad "66" smd rect
			(at -2.050034 -8.074914 90)
			(size 0.519938 1.4986)
			(layers "F.Cu" "F.Mask" "F.Paste")
			(net "M_B_CPU0_SA_CA<0>")
		)
		(pad "67" smd rect
			(at -2.050034 -7.22503 90)
			(size 0.519938 1.4986)
			(layers "F.Cu" "F.Mask" "F.Paste")
			(net "GND")
		)
		(pad "68" smd rect
			(at -2.050034 -6.374892 90)
			(size 0.519938 1.4986)
			(layers "F.Cu" "F.Mask" "F.Paste")
			(net "M_B_CPU0_SA_CA<2>")
		)
		(pad "69" smd rect
			(at -2.050034 -5.525008 90)
			(size 0.519938 1.4986)
			(layers "F.Cu" "F.Mask" "F.Paste")
			(net "GND")
		)
		(pad "70" smd rect
			(at -2.050034 -4.675124 90)
			(size 0.519938 1.4986)
			(layers "F.Cu" "F.Mask" "F.Paste")
			(net "M_B_CPU0_SA_CA<4>")
		)
		(pad "71" smd rect
			(at -2.050034 -3.824986 90)
			(size 0.519938 1.4986)
			(layers "F.Cu" "F.Mask" "F.Paste")
			(net "GND")
		)
		(pad "72" smd rect
			(at -2.050034 -2.975102 90)
			(size 0.519938 1.4986)
			(layers "F.Cu" "F.Mask" "F.Paste")
			(net "M_B_CPU0_SA_CA<6>")
		)
		(pad "73" smd rect
			(at -2.050034 -2.124964 90)
			(size 0.519938 1.4986)
			(layers "F.Cu" "F.Mask" "F.Paste")
			(net "GND")
		)
		(pad "74" smd rect
			(at -2.050034 -1.27508 90)
			(size 0.519938 1.4986)
			(layers "F.Cu" "F.Mask" "F.Paste")
			(net "M_B_CPU0_SA_PAR")
		)
		(pad "75" smd rect
			(at -2.050034 -0.424942 90)
			(size 0.519938 1.4986)
			(layers "F.Cu" "F.Mask" "F.Paste")
			(net "GND")
		)
		(pad "76" smd rect
			(at -2.050034 5.525008 90)
			(size 0.519938 1.4986)
			(layers "F.Cu" "F.Mask" "F.Paste")
			(net "M_B_CPU0_SB_CA<0>")
		)
		(pad "77" smd rect
			(at -2.050034 6.374892 90)
			(size 0.519938 1.4986)
			(layers "F.Cu" "F.Mask" "F.Paste")
			(net "GND")
		)
		(pad "78" smd rect
			(at -2.050034 7.22503 90)
			(size 0.519938 1.4986)
			(layers "F.Cu" "F.Mask" "F.Paste")
			(net "M_B_CPU0_SB_CA<2>")
		)
		(pad "79" smd rect
			(at -2.050034 8.074914 90)
			(size 0.519938 1.4986)
			(layers "F.Cu" "F.Mask" "F.Paste")
			(net "GND")
		)
		(pad "80" smd rect
			(at -2.050034 8.925052 90)
			(size 0.519938 1.4986)
			(layers "F.Cu" "F.Mask" "F.Paste")
			(net "M_B_CPU0_SB_CA<4>")
		)
		(pad "81" smd rect
			(at -2.050034 9.774936 90)
			(size 0.519938 1.4986)
			(layers "F.Cu" "F.Mask" "F.Paste")
			(net "GND")
		)
		(pad "82" smd rect
			(at -2.050034 10.625074 90)
			(size 0.519938 1.4986)
			(layers "F.Cu" "F.Mask" "F.Paste")
			(net "M_B_CPU0_SB_CA<6>")
		)
		(pad "83" smd rect
			(at -2.050034 11.474958 90)
			(size 0.519938 1.4986)
			(layers "F.Cu" "F.Mask" "F.Paste")
			(net "GND")
		)
		(pad "84" smd rect
			(at -2.050034 12.325096 90)
			(size 0.519938 1.4986)
			(layers "F.Cu" "F.Mask" "F.Paste")
			(net "M_B_CPU0_SB_CS_N<0>")
		)
		(pad "85" smd rect
			(at -2.050034 13.17498 90)
			(size 0.519938 1.4986)
			(layers "F.Cu" "F.Mask" "F.Paste")
			(net "GND")
		)
		(pad "86" smd rect
			(at -2.050034 14.025118 90)
			(size 0.519938 1.4986)
			(layers "F.Cu" "F.Mask" "F.Paste")
			(net "M_B_CPU0_SA_RSP<0>")
		)
		(pad "87" smd rect
			(at -2.050034 14.875002 90)
			(size 0.519938 1.4986)
			(layers "F.Cu" "F.Mask" "F.Paste")
			(net "M_B_CPU0_SB_RSP<0>")
		)
		(pad "88" smd rect
			(at -2.050034 15.724886 90)
			(size 0.519938 1.4986)
			(layers "F.Cu" "F.Mask" "F.Paste")
			(net "GND")
		)
		(pad "89" smd rect
			(at -2.050034 16.575024 90)
			(size 0.519938 1.4986)
			(layers "F.Cu" "F.Mask" "F.Paste")
			(net "M_B_CPU0_SB_CB<4>")
		)
		(pad "90" smd rect
			(at -2.050034 17.424908 90)
			(size 0.519938 1.4986)
			(layers "F.Cu" "F.Mask" "F.Paste")
			(net "GND")
		)
		(pad "91" smd rect
			(at -2.050034 18.275046 90)
			(size 0.519938 1.4986)
			(layers "F.Cu" "F.Mask" "F.Paste")
			(net "M_B_CPU0_SB_CB<5>")
		)
		(pad "92" smd rect
			(at -2.050034 19.12493 90)
			(size 0.519938 1.4986)
			(layers "F.Cu" "F.Mask" "F.Paste")
			(net "GND")
		)
	)
)
